(kicad_pcb
	(version 20260206)
	(generator "pcbnew")
	(generator_version "10.0")
	(general
		(thickness 1.6)
		(legacy_teardrops no)
	)
	(paper "A4")
	(title_block
		(title "Bryce Canyon_IOM_IOC_16318-2_OCP.brd")
		(comment 1 "Bryce Canyon / footprints 1219-1225 of 1605")
	)
	(layers
		(0 "F.Cu" signal "TOP")
		(4 "In1.Cu" signal "L2GND")
		(6 "In2.Cu" signal "L3")
		(8 "In3.Cu" signal "L4VCC")
		(10 "In4.Cu" signal "L5VCC")
		(12 "In5.Cu" signal "L6")
		(14 "In6.Cu" signal "L7GND")
		(2 "B.Cu" signal "BOTTOM")
		(9 "F.Adhes" user "F.Adhesive")
		(11 "B.Adhes" user "B.Adhesive")
		(13 "F.Paste" user "Package Geometry/Pastemask Top")
		(15 "B.Paste" user "Package Geometry/Pastemask Bottom")
		(5 "F.SilkS" user "Ref Des/Silkscreen Top")
		(7 "B.SilkS" user "Ref Des/Silkscreen Bottom")
		(1 "F.Mask" user "Board Geometry/Soldermask Top")
		(3 "B.Mask" user "Board Geometry/Soldermask Bottom")
		(17 "Dwgs.User" user "User.Drawings")
		(19 "Cmts.User" user "User.Comments")
		(21 "Eco1.User" user "User.Eco1")
		(23 "Eco2.User" user "User.Eco2")
		(25 "Edge.Cuts" user "Board Geometry/Outline")
		(27 "Margin" user)
		(31 "F.CrtYd" user "Package Geometry/Place Bound Top")
		(29 "B.CrtYd" user "Package Geometry/Place Bound Bottom")
		(35 "F.Fab" user "Ref Des/Assembly Top")
		(33 "B.Fab" user "Ref Des/Assembly Bottom")
	)
	(footprint ""
		(layer "B.Cu")
		(at 47.93234 -157.99308 90)
		(property "Reference" "C89"
			(at 0 0 90)
			(layer "B.SilkS")
			(hide yes)
			(effects
				(font
					(size 1.27 1.27)
				)
				(justify mirror)
			)
		)
		(property "Value" "SC4D7U25V5KX-1-GP"
			(at 0.0762 -6.1214 90)
			(unlocked yes)
			(layer "B.Fab")
			(hide yes)
			(effects
				(font
					(size 1.016 1.016)
					(thickness 0.1524)
				)
				(justify mirror)
			)
		)
		(property "Device Type" "C805H58"
			(at 0.0762 -8.1534 90)
			(unlocked yes)
			(layer "B.Fab")
			(hide yes)
			(effects
				(font
					(size 1.016 1.016)
					(thickness 0.1524)
				)
				(justify mirror)
			)
		)
		(duplicate_pad_numbers_are_jumpers no)
		(fp_line
			(start -0.635 0)
			(end 0.635 0)
			(stroke
				(width 0.508)
				(type default)
			)
			(layer "B.SilkS")
		)
		(fp_rect
			(start 0.9652 1.778)
			(end -0.9652 -1.778)
			(stroke
				(width 0)
				(type default)
			)
			(fill no)
			(layer "B.CrtYd")
		)
		(fp_poly
			(pts
				(xy 0.9652 -1.778) (xy -0.9652 -1.778) (xy -0.9652 1.778) (xy 0.9652 1.778)
			)
			(stroke
				(width 0)
				(type default)
			)
			(fill no)
			(layer "B.Fab")
		)
		(pad "1" smd rect
			(at 0 -0.9652 270)
			(size 1.397 1.143)
			(layers "B.Cu" "B.Mask" "B.Paste")
			(net "DACAV33")
		)
		(pad "2" smd rect
			(at 0 0.9652 270)
			(size 1.397 1.143)
			(layers "B.Cu" "B.Mask" "B.Paste")
			(net "GND")
		)
	)
	(footprint ""
		(layer "B.Cu")
		(at 47.272194 -131.694174 180)
		(property "Reference" "R613"
			(at 0 0 0)
			(layer "B.SilkS")
			(hide yes)
			(effects
				(font
					(size 1.27 1.27)
				)
				(justify mirror)
			)
		)
		(property "Value" "0R2J-2-GP"
			(at -0.064008 -3.993896 180)
			(unlocked yes)
			(layer "B.Fab")
			(hide yes)
			(effects
				(font
					(size 1.016 1.016)
					(thickness 0.1524)
				)
				(justify mirror)
			)
		)
		(property "Device Type" "R402H16"
			(at -0.064008 -5.517896 180)
			(unlocked yes)
			(layer "B.Fab")
			(hide yes)
			(effects
				(font
					(size 1.016 1.016)
					(thickness 0.1524)
				)
				(justify mirror)
			)
		)
		(duplicate_pad_numbers_are_jumpers no)
		(fp_line
			(start 0.508 -0.9398)
			(end 0.508 0.9398)
			(stroke
				(width 0.1524)
				(type default)
			)
			(layer "B.SilkS")
		)
		(fp_line
			(start -0.508 -0.9398)
			(end 0.508 -0.9398)
			(stroke
				(width 0.1524)
				(type default)
			)
			(layer "B.SilkS")
		)
		(fp_rect
			(start 0.508 0.9398)
			(end -0.508 -0.9398)
			(stroke
				(width 0)
				(type default)
			)
			(fill no)
			(layer "B.CrtYd")
		)
		(fp_rect
			(start 0.508 0.9398)
			(end -0.508 -0.9398)
			(stroke
				(width 0)
				(type default)
			)
			(fill no)
			(layer "B.Fab")
		)
		(pad "1" smd custom
			(at 0 -0.4445)
			(size 0.1397 0.1397)
			(layers "B.Cu" "B.Mask" "B.Paste")
			(net "PCIE_COMP_TO_IOM_RST_4")
			(options
				(clearance outline)
				(anchor circle)
			)
			(primitives
				(gr_poly
					(pts
						(arc
							(start -0.1778 0.2794)
							(mid -0.249642 0.249642)
							(end -0.2794 0.1778)
						)
						(arc
							(start -0.2794 -0.1778)
							(mid -0.249642 -0.249642)
							(end -0.1778 -0.2794)
						)
						(arc
							(start 0.1778 -0.2794)
							(mid 0.249642 -0.249642)
							(end 0.2794 -0.1778)
						)
						(arc
							(start 0.2794 0.1778)
							(mid 0.249642 0.249642)
							(end 0.1778 0.2794)
						)
					)
					(width 0)
					(fill yes)
				)
			)
		)
		(pad "2" smd custom
			(at 0 0.4445)
			(size 0.1397 0.1397)
			(layers "B.Cu" "B.Mask" "B.Paste")
			(net "PLTRST_R")
			(options
				(clearance outline)
				(anchor circle)
			)
			(primitives
				(gr_poly
					(pts
						(arc
							(start -0.1778 0.2794)
							(mid -0.249642 0.249642)
							(end -0.2794 0.1778)
						)
						(arc
							(start -0.2794 -0.1778)
							(mid -0.249642 -0.249642)
							(end -0.1778 -0.2794)
						)
						(arc
							(start 0.1778 -0.2794)
							(mid 0.249642 -0.249642)
							(end 0.2794 -0.1778)
						)
						(arc
							(start 0.2794 0.1778)
							(mid 0.249642 0.249642)
							(end 0.1778 0.2794)
						)
					)
					(width 0)
					(fill yes)
				)
			)
		)
	)
	(footprint ""
		(layer "B.Cu")
		(at 204.772768 -46.281086 90)
		(property "Reference" "R681"
			(at 0 0 90)
			(layer "B.SilkS")
			(hide yes)
			(effects
				(font
					(size 1.27 1.27)
				)
				(justify mirror)
			)
		)
		(property "Value" "10R2F-L-GP"
			(at -0.064008 -3.993896 90)
			(unlocked yes)
			(layer "B.Fab")
			(hide yes)
			(effects
				(font
					(size 1.016 1.016)
					(thickness 0.1524)
				)
				(justify mirror)
			)
		)
		(property "Device Type" "R402H14"
			(at -0.064008 -5.517896 90)
			(unlocked yes)
			(layer "B.Fab")
			(hide yes)
			(effects
				(font
					(size 1.016 1.016)
					(thickness 0.1524)
				)
				(justify mirror)
			)
		)
		(duplicate_pad_numbers_are_jumpers no)
		(fp_line
			(start 0.508 -0.9398)
			(end 0.508 0.9398)
			(stroke
				(width 0.1524)
				(type default)
			)
			(layer "B.SilkS")
		)
		(fp_line
			(start -0.508 -0.9398)
			(end 0.508 -0.9398)
			(stroke
				(width 0.1524)
				(type default)
			)
			(layer "B.SilkS")
		)
		(fp_rect
			(start 0.508 0.9398)
			(end -0.508 -0.9398)
			(stroke
				(width 0)
				(type default)
			)
			(fill no)
			(layer "B.CrtYd")
		)
		(fp_rect
			(start 0.508 0.9398)
			(end -0.508 -0.9398)
			(stroke
				(width 0)
				(type default)
			)
			(fill no)
			(layer "B.Fab")
		)
		(pad "1" smd custom
			(at 0 -0.4445 270)
			(size 0.1397 0.1397)
			(layers "B.Cu" "B.Mask" "B.Paste")
			(net "P1V8")
			(options
				(clearance outline)
				(anchor circle)
			)
			(primitives
				(gr_poly
					(pts
						(arc
							(start -0.1778 0.2794)
							(mid -0.249642 0.249642)
							(end -0.2794 0.1778)
						)
						(arc
							(start -0.2794 -0.1778)
							(mid -0.249642 -0.249642)
							(end -0.1778 -0.2794)
						)
						(arc
							(start 0.1778 -0.2794)
							(mid 0.249642 -0.249642)
							(end 0.2794 -0.1778)
						)
						(arc
							(start 0.2794 0.1778)
							(mid 0.249642 0.249642)
							(end 0.1778 0.2794)
						)
					)
					(width 0)
					(fill yes)
				)
			)
		)
		(pad "2" smd custom
			(at 0 0.4445 270)
			(size 0.1397 0.1397)
			(layers "B.Cu" "B.Mask" "B.Paste")
			(net "SHELL_PLL_VDD")
			(options
				(clearance outline)
				(anchor circle)
			)
			(primitives
				(gr_poly
					(pts
						(arc
							(start -0.1778 0.2794)
							(mid -0.249642 0.249642)
							(end -0.2794 0.1778)
						)
						(arc
							(start -0.2794 -0.1778)
							(mid -0.249642 -0.249642)
							(end -0.1778 -0.2794)
						)
						(arc
							(start 0.1778 -0.2794)
							(mid 0.249642 -0.249642)
							(end 0.2794 -0.1778)
						)
						(arc
							(start 0.2794 0.1778)
							(mid 0.249642 0.249642)
							(end 0.1778 0.2794)
						)
					)
					(width 0)
					(fill yes)
				)
			)
		)
	)
	(footprint ""
		(layer "B.Cu")
		(at 130.12166 -14.217142)
		(property "Reference" "R448"
			(at 0 0 0)
			(layer "B.SilkS")
			(hide yes)
			(effects
				(font
					(size 1.27 1.27)
				)
				(justify mirror)
			)
		)
		(property "Value" "5K1R2F-3-GP"
			(at -0.064008 -3.993896 0)
			(unlocked yes)
			(layer "B.Fab")
			(hide yes)
			(effects
				(font
					(size 1.016 1.016)
					(thickness 0.1524)
				)
				(justify mirror)
			)
		)
		(property "Device Type" "R402H16"
			(at -0.064008 -5.517896 0)
			(unlocked yes)
			(layer "B.Fab")
			(hide yes)
			(effects
				(font
					(size 1.016 1.016)
					(thickness 0.1524)
				)
				(justify mirror)
			)
		)
		(duplicate_pad_numbers_are_jumpers no)
		(fp_line
			(start -0.508 -0.9398)
			(end 0.508 -0.9398)
			(stroke
				(width 0.1524)
				(type default)
			)
			(layer "B.SilkS")
		)
		(fp_line
			(start 0.508 -0.9398)
			(end 0.508 0.9398)
			(stroke
				(width 0.1524)
				(type default)
			)
			(layer "B.SilkS")
		)
		(fp_rect
			(start 0.508 0.9398)
			(end -0.508 -0.9398)
			(stroke
				(width 0)
				(type default)
			)
			(fill no)
			(layer "B.CrtYd")
		)
		(fp_rect
			(start 0.508 0.9398)
			(end -0.508 -0.9398)
			(stroke
				(width 0)
				(type default)
			)
			(fill no)
			(layer "B.Fab")
		)
		(pad "1" smd custom
			(at 0 -0.4445 180)
			(size 0.1397 0.1397)
			(layers "B.Cu" "B.Mask" "B.Paste")
			(net "MB0_CM_UV_R")
			(options
				(clearance outline)
				(anchor circle)
			)
			(primitives
				(gr_poly
					(pts
						(arc
							(start -0.1778 0.2794)
							(mid -0.249642 0.249642)
							(end -0.2794 0.1778)
						)
						(arc
							(start -0.2794 -0.1778)
							(mid -0.249642 -0.249642)
							(end -0.1778 -0.2794)
						)
						(arc
							(start 0.1778 -0.2794)
							(mid 0.249642 -0.249642)
							(end 0.2794 -0.1778)
						)
						(arc
							(start 0.2794 0.1778)
							(mid 0.249642 0.249642)
							(end 0.1778 0.2794)
						)
					)
					(width 0)
					(fill yes)
				)
			)
		)
		(pad "2" smd custom
			(at 0 0.4445 180)
			(size 0.1397 0.1397)
			(layers "B.Cu" "B.Mask" "B.Paste")
			(net "AGND_CURRENT_MON")
			(options
				(clearance outline)
				(anchor circle)
			)
			(primitives
				(gr_poly
					(pts
						(arc
							(start -0.1778 0.2794)
							(mid -0.249642 0.249642)
							(end -0.2794 0.1778)
						)
						(arc
							(start -0.2794 -0.1778)
							(mid -0.249642 -0.249642)
							(end -0.1778 -0.2794)
						)
						(arc
							(start 0.1778 -0.2794)
							(mid 0.249642 -0.249642)
							(end 0.2794 -0.1778)
						)
						(arc
							(start 0.2794 0.1778)
							(mid 0.249642 0.249642)
							(end 0.1778 0.2794)
						)
					)
					(width 0)
					(fill yes)
				)
			)
		)
	)
	(footprint ""
		(layer "B.Cu")
		(at 203.7334 -56.9468 180)
		(property "Reference" "R591"
			(at 0 0 0)
			(layer "B.SilkS")
			(hide yes)
			(effects
				(font
					(size 1.27 1.27)
				)
				(justify mirror)
			)
		)
		(property "Value" "2K2R2F-GP"
			(at -0.064008 -3.993896 180)
			(unlocked yes)
			(layer "B.Fab")
			(hide yes)
			(effects
				(font
					(size 1.016 1.016)
					(thickness 0.1524)
				)
				(justify mirror)
			)
		)
		(property "Device Type" "R402H16"
			(at -0.064008 -5.517896 180)
			(unlocked yes)
			(layer "B.Fab")
			(hide yes)
			(effects
				(font
					(size 1.016 1.016)
					(thickness 0.1524)
				)
				(justify mirror)
			)
		)
		(duplicate_pad_numbers_are_jumpers no)
		(fp_line
			(start 0.508 -0.9398)
			(end 0.508 0.9398)
			(stroke
				(width 0.1524)
				(type default)
			)
			(layer "B.SilkS")
		)
		(fp_line
			(start -0.508 -0.9398)
			(end 0.508 -0.9398)
			(stroke
				(width 0.1524)
				(type default)
			)
			(layer "B.SilkS")
		)
		(fp_rect
			(start 0.508 0.9398)
			(end -0.508 -0.9398)
			(stroke
				(width 0)
				(type default)
			)
			(fill no)
			(layer "B.CrtYd")
		)
		(fp_rect
			(start 0.508 0.9398)
			(end -0.508 -0.9398)
			(stroke
				(width 0)
				(type default)
			)
			(fill no)
			(layer "B.Fab")
		)
		(pad "1" smd custom
			(at 0 -0.4445)
			(size 0.1397 0.1397)
			(layers "B.Cu" "B.Mask" "B.Paste")
			(net "P1V8")
			(options
				(clearance outline)
				(anchor circle)
			)
			(primitives
				(gr_poly
					(pts
						(arc
							(start -0.1778 0.2794)
							(mid -0.249642 0.249642)
							(end -0.2794 0.1778)
						)
						(arc
							(start -0.2794 -0.1778)
							(mid -0.249642 -0.249642)
							(end -0.1778 -0.2794)
						)
						(arc
							(start 0.1778 -0.2794)
							(mid 0.249642 -0.249642)
							(end 0.2794 -0.1778)
						)
						(arc
							(start 0.2794 0.1778)
							(mid 0.249642 0.249642)
							(end 0.1778 0.2794)
						)
					)
					(width 0)
					(fill yes)
				)
			)
		)
		(pad "2" smd custom
			(at 0 0.4445)
			(size 0.1397 0.1397)
			(layers "B.Cu" "B.Mask" "B.Paste")
			(net "SIO_LOAD_0")
			(options
				(clearance outline)
				(anchor circle)
			)
			(primitives
				(gr_poly
					(pts
						(arc
							(start -0.1778 0.2794)
							(mid -0.249642 0.249642)
							(end -0.2794 0.1778)
						)
						(arc
							(start -0.2794 -0.1778)
							(mid -0.249642 -0.249642)
							(end -0.1778 -0.2794)
						)
						(arc
							(start 0.1778 -0.2794)
							(mid 0.249642 -0.249642)
							(end 0.2794 -0.1778)
						)
						(arc
							(start 0.2794 0.1778)
							(mid 0.249642 0.249642)
							(end 0.1778 0.2794)
						)
					)
					(width 0)
					(fill yes)
				)
			)
		)
	)
	(footprint ""
		(layer "B.Cu")
		(at 155.321 -91.1606 90)
		(property "Reference" "C327"
			(at 0 0 90)
			(layer "B.SilkS")
			(hide yes)
			(effects
				(font
					(size 1.27 1.27)
				)
				(justify mirror)
			)
		)
		(property "Value" "SCD1U16V2KX-3GP"
			(at -1.1811 -2.7051 90)
			(unlocked yes)
			(layer "B.Fab")
			(hide yes)
			(effects
				(font
					(size 1.016 1.016)
					(thickness 0.1524)
				)
				(justify mirror)
			)
		)
		(property "Device Type" "C402H22"
			(at -1.1811 -4.2291 90)
			(unlocked yes)
			(layer "B.Fab")
			(hide yes)
			(effects
				(font
					(size 1.016 1.016)
					(thickness 0.1524)
				)
				(justify mirror)
			)
		)
		(duplicate_pad_numbers_are_jumpers no)
		(fp_rect
			(start 0.4318 0.9525)
			(end -0.4318 -0.9525)
			(stroke
				(width 0)
				(type default)
			)
			(fill no)
			(layer "B.CrtYd")
		)
		(fp_rect
			(start 0.4318 0.9525)
			(end -0.4318 -0.9525)
			(stroke
				(width 0)
				(type default)
			)
			(fill no)
			(layer "B.Fab")
		)
		(pad "1" smd custom
			(at 0 -0.4445 270)
			(size 0.1524 0.1524)
			(layers "B.Cu" "B.Mask" "B.Paste")
			(net "P1V8_STBY")
			(options
				(clearance outline)
				(anchor circle)
			)
			(primitives
				(gr_poly
					(pts
						(arc
							(start 0.3048 0.2032)
							(mid 0.275042 0.275042)
							(end 0.2032 0.3048)
						)
						(arc
							(start -0.2032 0.3048)
							(mid -0.275042 0.275042)
							(end -0.3048 0.2032)
						)
						(arc
							(start -0.3048 -0.2032)
							(mid -0.275042 -0.275042)
							(end -0.2032 -0.3048)
						)
						(arc
							(start 0.2032 -0.3048)
							(mid 0.275042 -0.275042)
							(end 0.3048 -0.2032)
						)
					)
					(width 0)
					(fill yes)
				)
			)
		)
		(pad "2" smd custom
			(at 0 0.4445 270)
			(size 0.1524 0.1524)
			(layers "B.Cu" "B.Mask" "B.Paste")
			(net "GND")
			(options
				(clearance outline)
				(anchor circle)
			)
			(primitives
				(gr_poly
					(pts
						(arc
							(start 0.3048 0.2032)
							(mid 0.275042 0.275042)
							(end 0.2032 0.3048)
						)
						(arc
							(start -0.2032 0.3048)
							(mid -0.275042 0.275042)
							(end -0.3048 0.2032)
						)
						(arc
							(start -0.3048 -0.2032)
							(mid -0.275042 -0.275042)
							(end -0.2032 -0.3048)
						)
						(arc
							(start 0.2032 -0.3048)
							(mid 0.275042 -0.275042)
							(end 0.3048 -0.2032)
						)
					)
					(width 0)
					(fill yes)
				)
			)
		)
	)
	(footprint ""
		(layer "B.Cu")
		(at 191.68999 -19.812 -90)
		(property "Reference" "C487"
			(at 0 0 90)
			(layer "B.SilkS")
			(hide yes)
			(effects
				(font
					(size 1.27 1.27)
				)
				(justify mirror)
			)
		)
		(property "Value" "SCD01U16V1KX-GP"
			(at 2.8321 -1.7399 270)
			(unlocked yes)
			(layer "B.Fab")
			(hide yes)
			(effects
				(font
					(size 1.016 1.016)
					(thickness 0.1524)
				)
				(justify mirror)
			)
		)
		(property "Device Type" "C0201H13"
			(at 2.8321 -3.2639 270)
			(unlocked yes)
			(layer "B.Fab")
			(hide yes)
			(effects
				(font
					(size 1.016 1.016)
					(thickness 0.1524)
				)
				(justify mirror)
			)
		)
		(duplicate_pad_numbers_are_jumpers no)
		(fp_rect
			(start 0.2794 0.6477)
			(end -0.2794 -0.6477)
			(stroke
				(width 0)
				(type default)
			)
			(fill no)
			(layer "B.CrtYd")
		)
		(fp_rect
			(start 0.2794 0.6477)
			(end -0.2794 -0.6477)
			(stroke
				(width 0)
				(type default)
			)
			(fill no)
			(layer "B.Fab")
		)
		(pad "1" smd custom
			(at 0 -0.2794 90)
			(size 0.0762 0.0762)
			(layers "B.Cu" "B.Mask" "B.Paste")
			(net "PHY_CON_A_TO_IOC_0_DP")
			(options
				(clearance outline)
				(anchor circle)
			)
			(primitives
				(gr_poly
					(pts
						(arc
							(start 0.1524 0.127)
							(mid 0.137521 0.162921)
							(end 0.1016 0.1778)
						)
						(arc
							(start -0.1016 0.1778)
							(mid -0.137521 0.162921)
							(end -0.1524 0.127)
						)
						(arc
							(start -0.1524 -0.127)
							(mid -0.137521 -0.162921)
							(end -0.1016 -0.1778)
						)
						(arc
							(start 0.1016 -0.1778)
							(mid 0.137521 -0.162921)
							(end 0.1524 -0.127)
						)
					)
					(width 0)
					(fill yes)
				)
			)
		)
		(pad "2" smd custom
			(at 0 0.2794 90)
			(size 0.0762 0.0762)
			(layers "B.Cu" "B.Mask" "B.Paste")
			(net "PHY_CON_A_TO_IOC_0_DP_C")
			(options
				(clearance outline)
				(anchor circle)
			)
			(primitives
				(gr_poly
					(pts
						(arc
							(start 0.1524 0.127)
							(mid 0.137521 0.162921)
							(end 0.1016 0.1778)
						)
						(arc
							(start -0.1016 0.1778)
							(mid -0.137521 0.162921)
							(end -0.1524 0.127)
						)
						(arc
							(start -0.1524 -0.127)
							(mid -0.137521 -0.162921)
							(end -0.1016 -0.1778)
						)
						(arc
							(start 0.1016 -0.1778)
							(mid 0.137521 -0.162921)
							(end 0.1524 -0.127)
						)
					)
					(width 0)
					(fill yes)
				)
			)
		)
	)
)
